# T6G (Grand Teton) — schematic netlist excerpt (pin names and nets, part order shuffled) for the footprints in the layout excerpt that follows; sources: Cadence DE-HDL packaged netlist, KiCad conversion of 04192023_DAF0TMB3IC0_F0TG_MB_C_brd_V02_OCP.brd

R1345  Q_RES  33.2 1% CHIP  pkg 0402LF  page 251 : A = SMB_INA230_3V3AUX_SDA ; B = SMB_INA230_6_3V3AUX_SDA_R
PR3937  Q_RES  120K 1% CHIP  pkg 0402LF  page 262 : A = HSC_MODE ; B = AGND_HSC

(kicad_pcb
	(version 20260206)
	(generator "pcbnew")
	(generator_version "10.0")
	(general
		(thickness 1.6)
		(legacy_teardrops no)
	)
	(paper "A4")
	(title_block
		(title "04192023_DAF0TMB3IC0_F0TG_MB_C_brd_V02_OCP.brd")
		(comment 1 "Grand Teton / footprints 1720-1721 of 8354")
	)
	(layers
		(0 "F.Cu" signal "TOP")
		(4 "In1.Cu" signal "GND")
		(6 "In2.Cu" signal "IN1")
		(8 "In3.Cu" signal "GND1")
		(10 "In4.Cu" signal "IN2")
		(12 "In5.Cu" signal "GND2")
		(14 "In6.Cu" signal "IN3")
		(16 "In7.Cu" signal "GND3")
		(18 "In8.Cu" signal "VCC")
		(20 "In9.Cu" signal "VCC1")
		(22 "In10.Cu" signal "GND4")
		(24 "In11.Cu" signal "IN4")
		(26 "In12.Cu" signal "GND5")
		(28 "In13.Cu" signal "IN5")
		(30 "In14.Cu" signal "GND6")
		(32 "In15.Cu" signal "IN6")
		(34 "In16.Cu" signal "GND7")
		(2 "B.Cu" signal "BOTTOM")
		(9 "F.Adhes" user "F.Adhesive")
		(11 "B.Adhes" user "B.Adhesive")
		(13 "F.Paste" user "Package Geometry/Pastemask Top")
		(15 "B.Paste" user "Package Geometry/Pastemask Bottom")
		(5 "F.SilkS" user "Ref Des/Silkscreen Top")
		(7 "B.SilkS" user "Ref Des/Silkscreen Bottom")
		(1 "F.Mask" user "Board Geometry/Soldermask Top")
		(3 "B.Mask" user "Board Geometry/Soldermask Bottom")
		(17 "Dwgs.User" user "User.Drawings")
		(19 "Cmts.User" user "User.Comments")
		(21 "Eco1.User" user "User.Eco1")
		(23 "Eco2.User" user "User.Eco2")
		(25 "Edge.Cuts" user "Board Geometry/Outline")
		(27 "Margin" user)
		(31 "F.CrtYd" user "Package Geometry/Place Bound Top")
		(29 "B.CrtYd" user "Package Geometry/Place Bound Bottom")
		(35 "F.Fab" user "Ref Des/Assembly Top")
		(33 "B.Fab" user "Ref Des/Assembly Bottom")
	)
	(footprint ""
		(layer "F.Cu")
		(at 191.41694 -403.611842)
		(property "Reference" "PR3937"
			(at 0 0 0)
			(layer "F.SilkS")
			(hide yes)
			(effects
				(font
					(size 1.27 1.27)
				)
			)
		)
		(property "Value" ""
			(at 0 0 0)
			(layer "F.Fab")
			(effects
				(font
					(size 1.27 1.27)
				)
			)
		)
		(duplicate_pad_numbers_are_jumpers no)
		(fp_line
			(start -0.7874 -0.4064)
			(end 0.7874 -0.4064)
			(stroke
				(width 0.1524)
				(type default)
			)
			(layer "F.SilkS")
		)
		(fp_line
			(start -0.7874 0.4064)
			(end -0.7874 -0.4064)
			(stroke
				(width 0.1524)
				(type default)
			)
			(layer "F.SilkS")
		)
		(fp_line
			(start 0.7874 -0.4064)
			(end 0.7874 0.4064)
			(stroke
				(width 0.1524)
				(type default)
			)
			(layer "F.SilkS")
		)
		(fp_line
			(start 0.7874 0.4064)
			(end -0.7874 0.4064)
			(stroke
				(width 0.1524)
				(type default)
			)
			(layer "F.SilkS")
		)
		(fp_line
			(start -0.67945 -0.305054)
			(end -0.12065 -0.305054)
			(stroke
				(width 0.1)
				(type default)
			)
			(layer "F.Fab")
		)
		(fp_line
			(start -0.67945 0.3048)
			(end -0.67945 -0.305054)
			(stroke
				(width 0.1)
				(type default)
			)
			(layer "F.Fab")
		)
		(fp_line
			(start -0.12065 -0.305054)
			(end -0.12065 -0.2794)
			(stroke
				(width 0.1)
				(type default)
			)
			(layer "F.Fab")
		)
		(fp_line
			(start -0.12065 -0.2794)
			(end 0.12065 -0.2794)
			(stroke
				(width 0.1)
				(type default)
			)
			(layer "F.Fab")
		)
		(fp_line
			(start -0.12065 0.2794)
			(end -0.12065 0.3048)
			(stroke
				(width 0.1)
				(type default)
			)
			(layer "F.Fab")
		)
		(fp_line
			(start -0.12065 0.3048)
			(end -0.67945 0.3048)
			(stroke
				(width 0.1)
				(type default)
			)
			(layer "F.Fab")
		)
		(fp_line
			(start 0.120396 0.2794)
			(end -0.12065 0.2794)
			(stroke
				(width 0.1)
				(type default)
			)
			(layer "F.Fab")
		)
		(fp_line
			(start 0.120396 0.3048)
			(end 0.120396 0.2794)
			(stroke
				(width 0.1)
				(type default)
			)
			(layer "F.Fab")
		)
		(fp_line
			(start 0.12065 -0.3048)
			(end 0.67945 -0.3048)
			(stroke
				(width 0.1)
				(type default)
			)
			(layer "F.Fab")
		)
		(fp_line
			(start 0.12065 -0.2794)
			(end 0.12065 -0.3048)
			(stroke
				(width 0.1)
				(type default)
			)
			(layer "F.Fab")
		)
		(fp_line
			(start 0.67945 -0.3048)
			(end 0.67945 0.3048)
			(stroke
				(width 0.1)
				(type default)
			)
			(layer "F.Fab")
		)
		(fp_line
			(start 0.67945 0.3048)
			(end 0.120396 0.3048)
			(stroke
				(width 0.1)
				(type default)
			)
			(layer "F.Fab")
		)
		(pad "1" smd circle
			(at -0.40005 0)
			(size 0 0)
			(layers "F.Cu" "F.Mask" "F.Paste")
			(net "HSC_MODE")
		)
		(pad "2" smd circle
			(at 0.40005 0)
			(size 0 0)
			(layers "F.Cu" "F.Mask" "F.Paste")
			(net "AGND_HSC")
		)
	)
	(footprint ""
		(layer "F.Cu")
		(at 299.72 -108.966 -90)
		(property "Reference" "R1345"
			(at 0 0 270)
			(layer "F.SilkS")
			(hide yes)
			(effects
				(font
					(size 1.27 1.27)
				)
			)
		)
		(property "Value" ""
			(at 0 0 270)
			(layer "F.Fab")
			(effects
				(font
					(size 1.27 1.27)
				)
			)
		)
		(duplicate_pad_numbers_are_jumpers no)
		(fp_line
			(start -0.7874 0.4064)
			(end -0.7874 -0.4064)
			(stroke
				(width 0.1524)
				(type default)
			)
			(layer "F.SilkS")
		)
		(fp_line
			(start 0.7874 0.4064)
			(end -0.7874 0.4064)
			(stroke
				(width 0.1524)
				(type default)
			)
			(layer "F.SilkS")
		)
		(fp_line
			(start -0.7874 -0.4064)
			(end 0.7874 -0.4064)
			(stroke
				(width 0.1524)
				(type default)
			)
			(layer "F.SilkS")
		)
		(fp_line
			(start 0.7874 -0.4064)
			(end 0.7874 0.4064)
			(stroke
				(width 0.1524)
				(type default)
			)
			(layer "F.SilkS")
		)
		(fp_line
			(start -0.67945 0.3048)
			(end -0.67945 -0.305054)
			(stroke
				(width 0.1)
				(type default)
			)
			(layer "F.Fab")
		)
		(fp_line
			(start -0.12065 0.3048)
			(end -0.67945 0.3048)
			(stroke
				(width 0.1)
				(type default)
			)
			(layer "F.Fab")
		)
		(fp_line
			(start 0.120396 0.3048)
			(end 0.120396 0.2794)
			(stroke
				(width 0.1)
				(type default)
			)
			(layer "F.Fab")
		)
		(fp_line
			(start 0.67945 0.3048)
			(end 0.120396 0.3048)
			(stroke
				(width 0.1)
				(type default)
			)
			(layer "F.Fab")
		)
		(fp_line
			(start -0.12065 0.2794)
			(end -0.12065 0.3048)
			(stroke
				(width 0.1)
				(type default)
			)
			(layer "F.Fab")
		)
		(fp_line
			(start 0.120396 0.2794)
			(end -0.12065 0.2794)
			(stroke
				(width 0.1)
				(type default)
			)
			(layer "F.Fab")
		)
		(fp_line
			(start -0.12065 -0.2794)
			(end 0.12065 -0.2794)
			(stroke
				(width 0.1)
				(type default)
			)
			(layer "F.Fab")
		)
		(fp_line
			(start 0.12065 -0.2794)
			(end 0.12065 -0.3048)
			(stroke
				(width 0.1)
				(type default)
			)
			(layer "F.Fab")
		)
		(fp_line
			(start 0.12065 -0.3048)
			(end 0.67945 -0.3048)
			(stroke
				(width 0.1)
				(type default)
			)
			(layer "F.Fab")
		)
		(fp_line
			(start 0.67945 -0.3048)
			(end 0.67945 0.3048)
			(stroke
				(width 0.1)
				(type default)
			)
			(layer "F.Fab")
		)
		(fp_line
			(start -0.67945 -0.305054)
			(end -0.12065 -0.305054)
			(stroke
				(width 0.1)
				(type default)
			)
			(layer "F.Fab")
		)
		(fp_line
			(start -0.12065 -0.305054)
			(end -0.12065 -0.2794)
			(stroke
				(width 0.1)
				(type default)
			)
			(layer "F.Fab")
		)
		(pad "1" smd circle
			(at -0.40005 0 270)
			(size 0 0)
			(layers "F.Cu" "F.Mask" "F.Paste")
			(net "SMB_INA230_3V3AUX_SDA")
		)
		(pad "2" smd circle
			(at 0.40005 0 270)
			(size 0 0)
			(layers "F.Cu" "F.Mask" "F.Paste")
			(net "SMB_INA230_6_3V3AUX_SDA_R")
		)
	)
)
